FILE_TYPE = CONNECTIVITY;
{Allegro Design Entry HDL 17.2-2016 S081 (4005846) 1/11/2022}
"PAGE_NUMBER" = 100;
0"NC";
1"P3V3_AUX\g";
2"P12V_S3_AUX_CPU1_NVDIMM\g";
3"P12V_S3_AUX_CPU1_NVDIMM\g";
4"P3V3_AUX\g";
5"GND\g";
6"GND\g";
7"GND\g";
8"GND\g";
9"GND\g";
10"M_B_CPU1_SA_DQ<31:0>";
11"M_B_CPU1_SA_CB<7:0>";
12"M_B_CPU1_SB_CB<7:0>";
13"M_B_CPU1_SA_CA<6:0>";
14"M_B_CPU1_SB_CA<6:0>";
15"M_B_CPU1_SB_DQ<31:0>";
16"M_B_CPU1_SB_DQS_DP<9:0>";
17"M_B_CPU1_SA_DQS_DP<9:0>";
18"M_B_CPU1_SB_DQS_DN<9:0>";
19"M_B_CPU1_SA_DQS_DN<9:0>";
20"PD_CHB_CPU1_DIMM1_SAA";
21"I3C_SPD_DDRABCD_CPU1_LVC1_SDA";
22"M_B_CPU1_ALERT_N";
23"RST_M_AB_CPU1_FPGA_N";
24"I3C_SPD_DDRABCD_CPU1_LVC1_SCL_R3";
25"I3C_SPD_DDRABCD_CPU1_LVC1_SCL";
26"PWRGD_CHB_CPU1_DIMM1";
27"TP_CHB_CPU1_DIMM1_FRU_6";
28"TP_CHB_CPU1_DIMM1_FRU_2";
29"TP_CHB_CPU1_DIMM1_FRU_5";
30"TP_CHB_CPU1_DIMM1_FRU_3";
31"TP_CHB_CPU1_DIMM1_FRU_1";
32"TP_CHB_CPU1_DIMM1_FRU_0";
33"M_B_CPU1_SB_DQS_DN<4>";
34"M_B_CPU1_SA_DQS_DN<8>";
35"M_B_CPU1_SA_DQS_DN<9>";
36"M_B_CPU1_SA_DQS_DN<7>";
37"M_B_CPU1_SA_DQS_DN<6>";
38"M_B_CPU1_SA_DQS_DN<5>";
39"M_B_CPU1_SA_DQS_DN<4>";
40"M_B_CPU1_SA_DQS_DN<3>";
41"M_B_CPU1_SA_DQS_DN<2>";
42"M_B_CPU1_SA_DQS_DN<1>";
43"M_B_CPU1_SA_DQS_DN<0>";
44"M_B_CPU1_SB_DQS_DN<9>";
45"M_B_CPU1_SB_DQS_DN<8>";
46"M_B_CPU1_SB_DQS_DN<7>";
47"M_B_CPU1_SB_DQS_DN<6>";
48"M_B_CPU1_SB_DQS_DN<5>";
49"M_B_CPU1_SB_DQS_DN<3>";
50"M_B_CPU1_SB_DQS_DN<2>";
51"M_B_CPU1_SB_DQS_DN<0>";
52"M_B_CPU1_SB_DQS_DN<1>";
53"M_B_CPU1_SA_DQS_DP<9>";
54"M_B_CPU1_SA_DQS_DP<8>";
55"M_B_CPU1_SA_DQS_DP<7>";
56"M_B_CPU1_SA_DQS_DP<6>";
57"M_B_CPU1_SA_DQS_DP<5>";
58"M_B_CPU1_SA_DQS_DP<4>";
59"M_B_CPU1_SA_DQS_DP<3>";
60"M_B_CPU1_SA_DQS_DP<2>";
61"M_B_CPU1_SA_DQS_DP<1>";
62"M_B_CPU1_SA_DQS_DP<0>";
63"M_B_CPU1_SB_DQS_DP<9>";
64"M_B_CPU1_SB_DQS_DP<8>";
65"M_B_CPU1_SB_DQS_DP<7>";
66"M_B_CPU1_SB_DQS_DP<6>";
67"M_B_CPU1_SB_DQS_DP<5>";
68"M_B_CPU1_SB_DQS_DP<4>";
69"M_B_CPU1_SB_DQS_DP<3>";
70"M_B_CPU1_SB_DQS_DP<2>";
71"M_B_CPU1_SB_DQS_DP<1>";
72"M_B_CPU1_SB_DQS_DP<0>";
73"M_B_CPU1_SB_CB<0>";
74"M_B_CPU1_SB_CB<1>";
75"M_B_CPU1_SB_CB<2>";
76"M_B_CPU1_SB_CB<3>";
77"M_B_CPU1_SA_DQ<29>";
78"M_B_CPU1_SA_DQ<10>";
79"M_B_CPU1_SB_CS_N<0>";
80"M_B_CPU1_CLK_DP<0>";
81"M_B_CPU1_CLK_DN<0>";
82"M_B_CPU1_SA_CB<4>";
83"M_B_CPU1_SB_DQ<30>";
84"TP_CHB_CPU1_DIMM1_FRU_4";
85"M_B_CPU1_SB_PAR";
86"M_B_CPU1_SA_PAR";
87"M_B_CPU1_SB_RSP<0>";
88"M_B_CPU1_SA_RSP<0>";
89"M_B_CPU1_SB_DQ<0>";
90"M_B_CPU1_SB_DQ<1>";
91"M_B_CPU1_SB_DQ<2>";
92"M_B_CPU1_SB_DQ<3>";
93"M_B_CPU1_SB_DQ<4>";
94"M_B_CPU1_SB_DQ<5>";
95"M_B_CPU1_SB_DQ<6>";
96"M_B_CPU1_SB_DQ<7>";
97"M_B_CPU1_SB_DQ<8>";
98"M_B_CPU1_SB_DQ<9>";
99"M_B_CPU1_SB_DQ<10>";
100"M_B_CPU1_SB_DQ<11>";
101"M_B_CPU1_SB_DQ<12>";
102"M_B_CPU1_SB_DQ<13>";
103"M_B_CPU1_SB_DQ<14>";
104"M_B_CPU1_SB_DQ<15>";
105"M_B_CPU1_SB_DQ<16>";
106"M_B_CPU1_SB_DQ<17>";
107"M_B_CPU1_SB_DQ<18>";
108"M_B_CPU1_SB_DQ<19>";
109"M_B_CPU1_SB_DQ<20>";
110"M_B_CPU1_SB_DQ<21>";
111"M_B_CPU1_SB_DQ<22>";
112"M_B_CPU1_SB_DQ<23>";
113"M_B_CPU1_SB_DQ<24>";
114"M_B_CPU1_SB_DQ<25>";
115"M_B_CPU1_SB_DQ<26>";
116"M_B_CPU1_SB_DQ<27>";
117"M_B_CPU1_SB_DQ<28>";
118"M_B_CPU1_SB_DQ<29>";
119"M_B_CPU1_SB_DQ<31>";
120"M_B_CPU1_SA_DQ<0>";
121"M_B_CPU1_SA_DQ<1>";
122"M_B_CPU1_SA_DQ<2>";
123"M_B_CPU1_SA_DQ<3>";
124"M_B_CPU1_SA_DQ<4>";
125"M_B_CPU1_SA_DQ<5>";
126"M_B_CPU1_SA_DQ<6>";
127"M_B_CPU1_SA_DQ<7>";
128"M_B_CPU1_SA_DQ<8>";
129"M_B_CPU1_SA_DQ<9>";
130"M_B_CPU1_SA_DQ<11>";
131"M_B_CPU1_SA_DQ<12>";
132"M_B_CPU1_SA_DQ<13>";
133"M_B_CPU1_SA_DQ<14>";
134"M_B_CPU1_SA_DQ<15>";
135"M_B_CPU1_SA_DQ<16>";
136"M_B_CPU1_SA_DQ<17>";
137"M_B_CPU1_SA_DQ<18>";
138"M_B_CPU1_SA_DQ<19>";
139"M_B_CPU1_SA_DQ<20>";
140"M_B_CPU1_SA_DQ<21>";
141"M_B_CPU1_SA_DQ<22>";
142"M_B_CPU1_SA_DQ<23>";
143"M_B_CPU1_SA_DQ<24>";
144"M_B_CPU1_SA_DQ<25>";
145"M_B_CPU1_SA_DQ<26>";
146"M_B_CPU1_SA_DQ<27>";
147"M_B_CPU1_SA_DQ<28>";
148"M_B_CPU1_SA_DQ<30>";
149"M_B_CPU1_SB_CS_N<1>";
150"M_B_CPU1_SA_CS_N<1>";
151"M_B_CPU1_SA_CS_N<0>";
152"M_B_CPU1_SB_CB<4>";
153"M_B_CPU1_SB_CB<5>";
154"M_B_CPU1_SB_CB<6>";
155"M_B_CPU1_SA_CB<0>";
156"M_B_CPU1_SA_CB<2>";
157"M_B_CPU1_SA_CB<3>";
158"M_B_CPU1_SA_CB<5>";
159"M_B_CPU1_SA_CB<6>";
160"M_B_CPU1_SB_CA<6>";
161"M_B_CPU1_SA_CA<6>";
162"M_B_CPU1_SB_CA<5>";
163"M_B_CPU1_SA_CA<5>";
164"M_B_CPU1_SB_CA<4>";
165"M_B_CPU1_SA_CA<4>";
166"M_B_CPU1_SB_CA<3>";
167"M_B_CPU1_SA_CA<3>";
168"M_B_CPU1_SB_CA<2>";
169"M_B_CPU1_SA_CA<2>";
170"M_B_CPU1_SB_CA<1>";
171"M_B_CPU1_SA_CA<1>";
172"M_B_CPU1_SB_CA<0>";
173"M_B_CPU1_SA_CA<0>";
174"M_B_CPU1_SB_CB<7>";
175"M_B_CPU1_SA_CB<1>";
176"M_B_CPU1_SA_CB<7>";
177"M_B_CPU1_SA_DQ<31>";
178"PD_CHB_CPU1_DIMM1_SAA";
%"TAP"
"1","(-575,3550)","0","standard","I100";
;
CDS_LIB"standard"
BODY_TYPE"PLUMBING"
HDL_TAP"TRUE";
"B \NAC \NWC"10;
"S \NAC"
BN"14"133;
%"TAP"
"1","(-575,3350)","0","standard","I101";
;
CDS_LIB"standard"
BODY_TYPE"PLUMBING"
HDL_TAP"TRUE";
"B \NAC \NWC"10;
"S \NAC"
BN"10"78;
%"TAP"
"1","(-575,3400)","0","standard","I102";
;
CDS_LIB"standard"
BODY_TYPE"PLUMBING"
HDL_TAP"TRUE";
"B \NAC \NWC"10;
"S \NAC"
BN"11"130;
%"TAP"
"1","(-575,3800)","0","standard","I103";
;
CDS_LIB"standard"
BODY_TYPE"PLUMBING"
HDL_TAP"TRUE";
"B \NAC \NWC"10;
"S \NAC"
BN"19"138;
%"TAP"
"1","(-575,3750)","0","standard","I104";
;
CDS_LIB"standard"
BODY_TYPE"PLUMBING"
HDL_TAP"TRUE";
"B \NAC \NWC"10;
"S \NAC"
BN"18"137;
%"TAP"
"1","(-575,3600)","0","standard","I105";
;
CDS_LIB"standard"
BODY_TYPE"PLUMBING"
HDL_TAP"TRUE";
"B \NAC \NWC"10;
"S \NAC"
BN"15"134;
%"TAP"
"1","(-575,3650)","0","standard","I106";
;
CDS_LIB"standard"
BODY_TYPE"PLUMBING"
HDL_TAP"TRUE";
"B \NAC \NWC"10;
"S \NAC"
BN"16"135;
%"TAP"
"1","(-575,3700)","0","standard","I107";
;
CDS_LIB"standard"
BODY_TYPE"PLUMBING"
HDL_TAP"TRUE";
"B \NAC \NWC"10;
"S \NAC"
BN"17"136;
%"TAP"
"1","(-575,4000)","0","standard","I108";
;
CDS_LIB"standard"
BODY_TYPE"PLUMBING"
HDL_TAP"TRUE";
"B \NAC \NWC"10;
"S \NAC"
BN"23"142;
%"TAP"
"1","(-575,4050)","0","standard","I109";
;
CDS_LIB"standard"
BODY_TYPE"PLUMBING"
HDL_TAP"TRUE";
"B \NAC \NWC"10;
"S \NAC"
BN"24"143;
%"TAP"
"1","(-575,3950)","0","standard","I110";
;
CDS_LIB"standard"
BODY_TYPE"PLUMBING"
HDL_TAP"TRUE";
"B \NAC \NWC"10;
"S \NAC"
BN"22"141;
%"TAP"
"1","(-575,3900)","0","standard","I111";
;
CDS_LIB"standard"
BODY_TYPE"PLUMBING"
HDL_TAP"TRUE";
"B \NAC \NWC"10;
"S \NAC"
BN"21"140;
%"TAP"
"1","(-575,3850)","0","standard","I112";
;
CDS_LIB"standard"
BODY_TYPE"PLUMBING"
HDL_TAP"TRUE";
"B \NAC \NWC"10;
"S \NAC"
BN"20"139;
%"TAP"
"1","(-575,4200)","0","standard","I113";
;
CDS_LIB"standard"
BODY_TYPE"PLUMBING"
HDL_TAP"TRUE";
"B \NAC \NWC"10;
"S \NAC"
BN"27"146;
%"TAP"
"1","(-575,4250)","0","standard","I114";
;
CDS_LIB"standard"
BODY_TYPE"PLUMBING"
HDL_TAP"TRUE";
"B \NAC \NWC"10;
"S \NAC"
BN"28"147;
%"TAP"
"1","(-575,4300)","0","standard","I115";
;
CDS_LIB"standard"
BODY_TYPE"PLUMBING"
HDL_TAP"TRUE";
"B \NAC \NWC"10;
"S \NAC"
BN"29"77;
%"TAP"
"1","(-575,4150)","0","standard","I116";
;
CDS_LIB"standard"
BODY_TYPE"PLUMBING"
HDL_TAP"TRUE";
"B \NAC \NWC"10;
"S \NAC"
BN"26"145;
%"TAP"
"1","(-575,4100)","0","standard","I117";
;
CDS_LIB"standard"
BODY_TYPE"PLUMBING"
HDL_TAP"TRUE";
"B \NAC \NWC"10;
"S \NAC"
BN"25"144;
%"TAP"
"1","(-575,4400)","0","standard","I118";
;
CDS_LIB"standard"
BODY_TYPE"PLUMBING"
HDL_TAP"TRUE";
"B \NAC \NWC"10;
"S \NAC"
BN"31"177;
%"TAP"
"1","(-575,4350)","0","standard","I119";
;
CDS_LIB"standard"
BODY_TYPE"PLUMBING"
HDL_TAP"TRUE";
"B \NAC \NWC"10;
"S \NAC"
BN"30"148;
%"UNIVERSAL_GND"
"1","(1150,150)","0","logical_power","I120";
;
HDL_POWER"GND"
CDS_LIB"logical_power";
"A"5;
%"Q_CAP"
"1","(1150,525)","0","pure_quanta","I121";
;
PART_NUMBER"CH5221MEB00"
MATERIAL"X6S"
TOLERANCE"20%"
VALUE"2.2UF"
VOLTAGE"6.3V"
PACK_TYPE"C0402"
$LOCATION"C56"
CDS_LIB"pure_quanta"
CDS_LOCATION"C56"
$SEC"1"
CDS_SEC"1";
"B"
$PN"2"5;
"A"
$PN"1"1;
%"Q_CAP"
"1","(2150,525)","0","pure_quanta","I122";
;
PART_NUMBER"CH6103KEA00"
PACK_TYPE"C0805"
TOLERANCE"10%"
VOLTAGE"16V"
VALUE"10UF"
MATERIAL"X6S"
$LOCATION"C57"
CDS_LIB"pure_quanta"
CDS_LOCATION"C57"
$SEC"1"
CDS_SEC"1";
"B"
$PN"2"6;
"A"
$PN"1"2;
%"UNIVERSAL_GND"
"1","(2775,150)","0","logical_power","I123";
;
HDL_POWER"GND"
CDS_LIB"logical_power";
"A"6;
%"Q_CAP"
"1","(2775,525)","0","pure_quanta","I124";
;
PART_NUMBER"CH6103KEA00"
PACK_TYPE"C0805"
TOLERANCE"10%"
VOLTAGE"16V"
VALUE"10UF"
MATERIAL"X6S"
$LOCATION"C58"
CDS_LIB"pure_quanta"
CDS_LOCATION"C58"
$SEC"1"
CDS_SEC"1";
"B"
$PN"2"6;
"A"
$PN"1"2;
%"VCC_CORE"
"1","(1150,850)","0","logical_power","I125";
;
HDL_POWER"P3V3_AUX"
CDS_LIB"logical_power";
"A"1;
%"VCC_CORE"
"1","(2150,850)","0","logical_power","I129";
;
HDL_POWER"P12V_S3_AUX_CPU1_NVDIMM"
CDS_LIB"logical_power";
"A"2;
%"VCC_CORE"
"1","(-3050,2275)","0","logical_power","I13";
;
HDL_POWER"P3V3_AUX"
CDS_LIB"logical_power";
"A"4;
%"TAP"
"1","(2175,2450)","0","standard","I130";
;
CDS_LIB"standard"
BODY_TYPE"PLUMBING"
HDL_TAP"TRUE";
"B \NAC \NWC"16;
"S \NAC"
BN"0"72;
%"TAP"
"1","(2350,2400)","0","standard","I131";
;
CDS_LIB"standard"
BODY_TYPE"PLUMBING"
HDL_TAP"TRUE";
"B \NAC \NWC"18;
"S \NAC"
BN"0"51;
%"TAP"
"1","(2350,2500)","0","standard","I132";
;
CDS_LIB"standard"
BODY_TYPE"PLUMBING"
HDL_TAP"TRUE";
"B \NAC \NWC"18;
"S \NAC"
BN"1"52;
%"TAP"
"1","(2175,2650)","0","standard","I133";
;
CDS_LIB"standard"
BODY_TYPE"PLUMBING"
HDL_TAP"TRUE";
"B \NAC \NWC"16;
"S \NAC"
BN"2"70;
%"TAP"
"1","(2175,2550)","0","standard","I134";
;
CDS_LIB"standard"
BODY_TYPE"PLUMBING"
HDL_TAP"TRUE";
"B \NAC \NWC"16;
"S \NAC"
BN"1"71;
%"TAP"
"1","(2175,2750)","0","standard","I135";
;
CDS_LIB"standard"
BODY_TYPE"PLUMBING"
HDL_TAP"TRUE";
"B \NAC \NWC"16;
"S \NAC"
BN"3"69;
%"TAP"
"1","(2175,3050)","0","standard","I136";
;
CDS_LIB"standard"
BODY_TYPE"PLUMBING"
HDL_TAP"TRUE";
"B \NAC \NWC"16;
"S \NAC"
BN"6"66;
%"TAP"
"1","(2175,2950)","0","standard","I137";
;
CDS_LIB"standard"
BODY_TYPE"PLUMBING"
HDL_TAP"TRUE";
"B \NAC \NWC"16;
"S \NAC"
BN"5"67;
%"TAP"
"1","(2175,2850)","0","standard","I138";
;
CDS_LIB"standard"
BODY_TYPE"PLUMBING"
HDL_TAP"TRUE";
"B \NAC \NWC"16;
"S \NAC"
BN"4"68;
%"TAP"
"1","(2175,3250)","0","standard","I139";
;
CDS_LIB"standard"
BODY_TYPE"PLUMBING"
HDL_TAP"TRUE";
"B \NAC \NWC"16;
"S \NAC"
BN"8"64;
%"TAP"
"1","(2175,3150)","0","standard","I140";
;
CDS_LIB"standard"
BODY_TYPE"PLUMBING"
HDL_TAP"TRUE";
"B \NAC \NWC"16;
"S \NAC"
BN"7"65;
%"TAP"
"1","(2175,3350)","0","standard","I141";
;
CDS_LIB"standard"
BODY_TYPE"PLUMBING"
HDL_TAP"TRUE";
"B \NAC \NWC"16;
"S \NAC"
BN"9"63;
%"TAP"
"1","(2175,3500)","0","standard","I142";
;
CDS_LIB"standard"
BODY_TYPE"PLUMBING"
HDL_TAP"TRUE";
"B \NAC \NWC"17;
"S \NAC"
BN"0"62;
%"TAP"
"1","(2350,2600)","0","standard","I143";
;
CDS_LIB"standard"
BODY_TYPE"PLUMBING"
HDL_TAP"TRUE";
"B \NAC \NWC"18;
"S \NAC"
BN"2"50;
%"TAP"
"1","(2350,2700)","0","standard","I144";
;
CDS_LIB"standard"
BODY_TYPE"PLUMBING"
HDL_TAP"TRUE";
"B \NAC \NWC"18;
"S \NAC"
BN"3"49;
%"TAP"
"1","(2350,2800)","0","standard","I145";
;
CDS_LIB"standard"
BODY_TYPE"PLUMBING"
HDL_TAP"TRUE";
"B \NAC \NWC"18;
"S \NAC"
BN"4"33;
%"TAP"
"1","(2350,2900)","0","standard","I146";
;
CDS_LIB"standard"
BODY_TYPE"PLUMBING"
HDL_TAP"TRUE";
"B \NAC \NWC"18;
"S \NAC"
BN"5"48;
%"TAP"
"1","(2350,3000)","0","standard","I147";
;
CDS_LIB"standard"
BODY_TYPE"PLUMBING"
HDL_TAP"TRUE";
"B \NAC \NWC"18;
"S \NAC"
BN"6"47;
%"TAP"
"1","(2350,3100)","0","standard","I148";
;
CDS_LIB"standard"
BODY_TYPE"PLUMBING"
HDL_TAP"TRUE";
"B \NAC \NWC"18;
"S \NAC"
BN"7"46;
%"TAP"
"1","(2350,3200)","0","standard","I149";
;
CDS_LIB"standard"
BODY_TYPE"PLUMBING"
HDL_TAP"TRUE";
"B \NAC \NWC"18;
"S \NAC"
BN"8"45;
%"TAP"
"1","(2350,3300)","0","standard","I150";
;
CDS_LIB"standard"
BODY_TYPE"PLUMBING"
HDL_TAP"TRUE";
"B \NAC \NWC"18;
"S \NAC"
BN"9"44;
%"TAP"
"1","(2350,3550)","0","standard","I151";
;
CDS_LIB"standard"
BODY_TYPE"PLUMBING"
HDL_TAP"TRUE";
"B \NAC \NWC"19;
"S \NAC"
BN"1"42;
%"TAP"
"1","(2350,3450)","0","standard","I152";
;
CDS_LIB"standard"
BODY_TYPE"PLUMBING"
HDL_TAP"TRUE";
"B \NAC \NWC"19;
"S \NAC"
BN"0"43;
%"TAP"
"1","(2175,3600)","0","standard","I153";
;
CDS_LIB"standard"
BODY_TYPE"PLUMBING"
HDL_TAP"TRUE";
"B \NAC \NWC"17;
"S \NAC"
BN"1"61;
%"TAP"
"1","(2175,3800)","0","standard","I154";
;
CDS_LIB"standard"
BODY_TYPE"PLUMBING"
HDL_TAP"TRUE";
"B \NAC \NWC"17;
"S \NAC"
BN"3"59;
%"TAP"
"1","(2175,3700)","0","standard","I155";
;
CDS_LIB"standard"
BODY_TYPE"PLUMBING"
HDL_TAP"TRUE";
"B \NAC \NWC"17;
"S \NAC"
BN"2"60;
%"TAP"
"1","(2175,4000)","0","standard","I156";
;
CDS_LIB"standard"
BODY_TYPE"PLUMBING"
HDL_TAP"TRUE";
"B \NAC \NWC"17;
"S \NAC"
BN"5"57;
%"TAP"
"1","(2175,3900)","0","standard","I157";
;
CDS_LIB"standard"
BODY_TYPE"PLUMBING"
HDL_TAP"TRUE";
"B \NAC \NWC"17;
"S \NAC"
BN"4"58;
%"TAP"
"1","(2175,4300)","0","standard","I158";
;
CDS_LIB"standard"
BODY_TYPE"PLUMBING"
HDL_TAP"TRUE";
"B \NAC \NWC"17;
"S \NAC"
BN"8"54;
%"TAP"
"1","(2175,4200)","0","standard","I159";
;
CDS_LIB"standard"
BODY_TYPE"PLUMBING"
HDL_TAP"TRUE";
"B \NAC \NWC"17;
"S \NAC"
BN"7"55;
%"TAP"
"1","(2175,4100)","0","standard","I160";
;
CDS_LIB"standard"
BODY_TYPE"PLUMBING"
HDL_TAP"TRUE";
"B \NAC \NWC"17;
"S \NAC"
BN"6"56;
%"TAP"
"1","(2175,4400)","0","standard","I161";
;
CDS_LIB"standard"
BODY_TYPE"PLUMBING"
HDL_TAP"TRUE";
"B \NAC \NWC"17;
"S \NAC"
BN"9"53;
%"TAP"
"1","(2350,3650)","0","standard","I162";
;
CDS_LIB"standard"
BODY_TYPE"PLUMBING"
HDL_TAP"TRUE";
"B \NAC \NWC"19;
"S \NAC"
BN"2"41;
%"TAP"
"1","(2350,3750)","0","standard","I163";
;
CDS_LIB"standard"
BODY_TYPE"PLUMBING"
HDL_TAP"TRUE";
"B \NAC \NWC"19;
"S \NAC"
BN"3"40;
%"TAP"
"1","(2350,3850)","0","standard","I164";
;
CDS_LIB"standard"
BODY_TYPE"PLUMBING"
HDL_TAP"TRUE";
"B \NAC \NWC"19;
"S \NAC"
BN"4"39;
%"TAP"
"1","(2350,3950)","0","standard","I165";
;
CDS_LIB"standard"
BODY_TYPE"PLUMBING"
HDL_TAP"TRUE";
"B \NAC \NWC"19;
"S \NAC"
BN"5"38;
%"TAP"
"1","(2350,4050)","0","standard","I166";
;
CDS_LIB"standard"
BODY_TYPE"PLUMBING"
HDL_TAP"TRUE";
"B \NAC \NWC"19;
"S \NAC"
BN"6"37;
%"TAP"
"1","(2350,4150)","0","standard","I167";
;
CDS_LIB"standard"
BODY_TYPE"PLUMBING"
HDL_TAP"TRUE";
"B \NAC \NWC"19;
"S \NAC"
BN"7"36;
%"TAP"
"1","(2350,4250)","0","standard","I168";
;
CDS_LIB"standard"
BODY_TYPE"PLUMBING"
HDL_TAP"TRUE";
"B \NAC \NWC"19;
"S \NAC"
BN"8"34;
%"TAP"
"1","(2350,4350)","0","standard","I169";
;
CDS_LIB"standard"
BODY_TYPE"PLUMBING"
HDL_TAP"TRUE";
"B \NAC \NWC"19;
"S \NAC"
BN"9"35;
%"UNIVERSAL_GND"
"1","(3850,700)","0","logical_power","I174";
;
HDL_POWER"GND"
CDS_LIB"logical_power";
"A"7;
%"SCONN288_ADR50017P130CC"
"3","(4700,2775)","0","pure_quanta","I175";
;
PART_NUMBER"DFHST8FS461"
MATERIAL"IO"
PART_TYPE"SMLF"
VALUE"SCONN288_ADR50017-P130CC"
$LOCATION"J19"
NEEDS_NO_SIZE"TRUE"
CDS_LMAN_SYM_OUTLINE"-450,1775,450,-1775"
CDS_LIB"pure_quanta"
CDS_LOCATION"J19"
$SEC"3"
CDS_SEC"3";
"G3"
$PN"G3"8;
"G2"
$PN"G2"8;
"G1"
$PN"G1"8;
"VSS62"
$PN"141"8;
"VSS61"
$PN"139"8;
"VSS60"
$PN"136"8;
"VSS58"
$PN"132"8;
"VSS104"
$PN"240"7;
"VSS102"
$PN"235"7;
"VSS100"
$PN"230"7;
"VIN_BULK2"
$PN"146"3;
"VIN_BULK1"
$PN"145"3;
"VIN_BULK0"
$PN"1"3;
"VSS126"
$PN"288"7;
"VSS125"
$PN"286"7;
"VSS124"
$PN"284"7;
"VSS123"
$PN"281"7;
"VSS122"
$PN"279"7;
"VSS121"
$PN"277"7;
"VSS120"
$PN"275"7;
"VSS119"
$PN"273"7;
"VSS118"
$PN"270"7;
"VSS117"
$PN"268"7;
"VSS116"
$PN"266"7;
"VSS115"
$PN"264"7;
"VSS114"
$PN"262"7;
"VSS113"
$PN"259"7;
"VSS112"
$PN"257"7;
"VSS111"
$PN"255"7;
"VSS110"
$PN"253"7;
"VSS109"
$PN"251"7;
"VSS108"
$PN"248"7;
"VSS107"
$PN"246"7;
"VSS106"
$PN"244"7;
"VSS105"
$PN"242"7;
"VSS103"
$PN"237"7;
"VSS101"
$PN"233"7;
"VSS99"
$PN"228"7;
"VSS98"
$PN"226"7;
"VSS97"
$PN"224"7;
"VSS96"
$PN"222"7;
"VSS95"
$PN"219"7;
"VSS94"
$PN"216"7;
"VSS93"
$PN"214"7;
"VSS92"
$PN"212"7;
"VSS91"
$PN"210"7;
"VSS90"
$PN"208"7;
"VSS89"
$PN"206"7;
"VSS88"
$PN"204"7;
"VSS87"
$PN"202"7;
"VSS86"
$PN"199"7;
"VSS85"
$PN"197"7;
"VSS84"
$PN"195"7;
"VSS83"
$PN"193"7;
"VSS82"
$PN"191"7;
"VSS81"
$PN"188"7;
"VSS80"
$PN"186"7;
"VSS79"
$PN"184"7;
"VSS78"
$PN"182"7;
"VSS77"
$PN"180"7;
"VSS76"
$PN"177"7;
"VSS75"
$PN"175"7;
"VSS74"
$PN"173"7;
"VSS73"
$PN"171"7;
"VSS72"
$PN"169"7;
"VSS71"
$PN"166"7;
"VSS70"
$PN"164"7;
"VSS69"
$PN"162"7;
"VSS68"
$PN"160"7;
"VSS67"
$PN"158"7;
"VSS66"
$PN"155"7;
"VSS65"
$PN"153"7;
"VSS64"
$PN"151"7;
"VSS63"
$PN"143"8;
"VSS59"
$PN"134"8;
"VSS57"
$PN"130"8;
"VSS56"
$PN"128"8;
"VSS55"
$PN"125"8;
"VSS54"
$PN"123"8;
"VSS53"
$PN"121"8;
"VSS52"
$PN"119"8;
"VSS51"
$PN"117"8;
"VSS50"
$PN"114"8;
"VSS49"
$PN"112"8;
"VSS48"
$PN"110"8;
"VSS47"
$PN"108"8;
"VSS46"
$PN"106"8;
"VSS45"
$PN"103"8;
"VSS44"
$PN"101"8;
"VSS43"
$PN"99"8;
"VSS42"
$PN"97"8;
"VSS41"
$PN"95"8;
"VSS40"
$PN"92"8;
"VSS39"
$PN"90"8;
"VSS38"
$PN"88"8;
"VSS37"
$PN"85"8;
"VSS36"
$PN"83"8;
"VSS35"
$PN"81"8;
"VSS34"
$PN"79"8;
"VSS33"
$PN"77"8;
"VSS32"
$PN"75"8;
"VSS31"
$PN"73"8;
"VSS30"
$PN"71"8;
"VSS29"
$PN"69"8;
"VSS28"
$PN"67"8;
"VSS27"
$PN"65"8;
"VSS26"
$PN"63"8;
"VSS25"
$PN"61"8;
"VSS24"
$PN"59"8;
"VSS23"
$PN"57"8;
"VSS22"
$PN"54"8;
"VSS21"
$PN"52"8;
"VSS20"
$PN"50"8;
"VSS19"
$PN"48"8;
"VSS18"
$PN"46"8;
"VSS17"
$PN"43"8;
"VSS16"
$PN"41"8;
"VSS15"
$PN"39"8;
"VSS14"
$PN"37"8;
"VSS13"
$PN"35"8;
"VSS12"
$PN"32"8;
"VSS11"
$PN"30"8;
"VSS10"
$PN"28"8;
"VSS9"
$PN"26"8;
"VSS8"
$PN"24"8;
"VSS7"
$PN"21"8;
"VSS6"
$PN"19"8;
"VSS5"
$PN"17"8;
"VSS4"
$PN"15"8;
"VSS3"
$PN"13"8;
"VSS2"
$PN"10"8;
"VSS1"
$PN"8"8;
"VSS0"
$PN"6"8;
%"UNIVERSAL_GND"
"1","(5550,700)","0","logical_power","I176";
;
HDL_POWER"GND"
CDS_LIB"logical_power";
"A"8;
%"VCC_CORE"
"1","(3850,4950)","0","logical_power","I177";
;
HDL_POWER"P12V_S3_AUX_CPU1_NVDIMM"
CDS_LIB"logical_power";
"A"3;
%"SCONN288_ADR50017P130CC"
"2","(1275,3400)","0","pure_quanta","I178";
;
PART_NUMBER"DFHST8FS461"
MATERIAL"IO"
PART_TYPE"SMLF"
VALUE"SCONN288_ADR50017-P130CC"
LOCATION"J19"
NEEDS_NO_SIZE"TRUE"
CDS_LMAN_SYM_OUTLINE"-600,1150,600,-1150"
CDS_LIB"pure_quanta"
$SEC"2"
CDS_SEC"2";
"DQS7_A_C||TDQS7_A_C \B"
$PN"178"36;
"DQS6_A_T||TDQS6_A_T"
$PN"168"56;
"DQS8_B_T||TDQS8_B_T"
$PN"283"64;
"DQS8_B_C||TDQS8_B_C \B"
$PN"282"45;
"DQS7_B_T||TDQS7_B_T"
$PN"272"65;
"DQS0_A_C \B"
$PN"12"43;
"DQS0_A_T"
$PN"11"62;
"DQS0_B_C \B"
$PN"105"51;
"DQS0_B_T"
$PN"104"72;
"DQS1_A_C \B"
$PN"23"42;
"DQS1_A_T"
$PN"22"61;
"DQS1_B_C \B"
$PN"116"52;
"DQS1_B_T"
$PN"115"71;
"DQS2_A_C \B"
$PN"34"41;
"DQS2_A_T"
$PN"33"60;
"DQS2_B_C \B"
$PN"127"50;
"DQS2_B_T"
$PN"126"70;
"DQS3_A_C \B"
$PN"45"40;
"DQS3_A_T"
$PN"44"59;
"DQS3_B_C \B"
$PN"138"49;
"DQS3_B_T"
$PN"137"69;
"DQS4_A_C \B"
$PN"56"39;
"DQS4_A_T"
$PN"55"58;
"DQS4_B_C \B"
$PN"238"33;
"DQS4_B_T"
$PN"239"68;
"DQS5_A_C||TDQS5_A_C||DQS5_A_T||TDQS5_A_T \B"
$PN"156"38;
"DQS5_A_T||TDQS5_A_T"
$PN"157"57;
"DQS5_B_C||TDQS5_B_C \B"
$PN"249"48;
"DQS5_B_T||TDQS5_B_T"
$PN"250"67;
"DQS6_A_C||TDQS6_A_C||DQS6_A_T||TDQS6_A_T \B"
$PN"167"37;
"DQS6_B_C||TDQS6_B_C \B"
$PN"260"47;
"DQS6_B_T||TDQS6_B_T"
$PN"261"66;
"DQS7_A_T||TDQS7_A_T"
$PN"179"55;
"DQS7_B_C||TDQS7_B_C \B"
$PN"271"46;
"DQS8_A_C||TDQS8_A_C \B"
$PN"189"34;
"DQS8_A_T||TDQS8_A_T"
$PN"190"54;
"DQS9_A_C||TDQS9_A_C \B"
$PN"200"35;
"DQS9_A_T||TDQS9_A_T"
$PN"201"53;
"DQS9_B_C||TDQS9_B_C \B"
$PN"94"44;
"DQS9_B_T||TDQS9_B_T||DBI4_B_N"
$PN"93"63;
%"Q_RES"
"1","(-3175,1675)","0","pure_quanta","I180";
;
PART_NUMBER"CS04992FB07"
MATERIAL"CHIP"
VALUE"49.9"
$LOCATION"R3893"
CDS_LIB"pure_quanta"
PACK_TYPE"0402LF"
TOLERANCE"1%"
WATTAGE"1/16W"
CDS_LOCATION"R3893"
$SEC"1"
CDS_SEC"1";
"B"
$PN"2"25;
"A"
$PN"1"24;
%"UNIVERSAL_GND"
"1","(-2000,25)","0","logical_power","I2";
;
HDL_POWER"GND"
CDS_LIB"logical_power";
"A"9;
%"SCONN288_ADR50017P130CC"
"1","(-1400,2675)","0","pure_quanta","I25";
;
PART_NUMBER"DFHST8FS461"
MATERIAL"IO"
VALUE"SCONN288_ADR50017-P130CC"
PART_TYPE"SMLF"
$LOCATION"J19"
NEEDS_NO_SIZE"TRUE"
CDS_LMAN_SYM_OUTLINE"-450,1875,450,-1875"
CDS_LIB"pure_quanta"
CDS_LOCATION"J19"
$SEC"1"
CDS_SEC"1";
"DQ31_A"
$PN"194"177;
"CB7_A"
$PN"205"176;
"CB4_A"
$PN"58"82;
"CB1_A"
$PN"53"175;
"CB7_B"
$PN"236"174;
"ALERT_N \B"
$PN"62"22;
"CA0_A"
$PN"66"173;
"CA0_B"
$PN"76"172;
"CA1_A"
$PN"211"171;
"CA1_B"
$PN"221"170;
"CA2_A"
$PN"68"169;
"CA2_B"
$PN"78"168;
"CA3_A"
$PN"213"167;
"CA3_B"
$PN"223"166;
"CA4_A"
$PN"70"165;
"CA4_B"
$PN"80"164;
"CA5_A"
$PN"215"163;
"CA5_B"
$PN"225"162;
"CA6_A"
$PN"72"161;
"CA6_B"
$PN"82"160;
"CB6_A"
$PN"203"159;
"CB5_A"
$PN"60"158;
"CB3_A"
$PN"198"157;
"CB2_A"
$PN"196"156;
"CB0_A"
$PN"51"155;
"CB6_B"
$PN"234"154;
"CB5_B"
$PN"91"153;
"CB4_B"
$PN"89"152;
"CB3_B"
$PN"243"76;
"CB2_B"
$PN"241"75;
"CB1_B"
$PN"98"74;
"CB0_B"
$PN"96"73;
"CK_C \B"
$PN"218"81;
"CK_T"
$PN"217"80;
"CS0_A_N"
$PN"64"151;
"CS0_B_N"
$PN"84"79;
"CS1_A_N"
$PN"209"150;
"CS1_B_N"
$PN"229"149;
"DQ30_A"
$PN"192"148;
"DQ29_A"
$PN"49"77;
"DQ28_A"
$PN"47"147;
"DQ27_A"
$PN"187"146;
"DQ26_A"
$PN"185"145;
"DQ25_A"
$PN"42"144;
"DQ24_A"
$PN"40"143;
"DQ23_A"
$PN"183"142;
"DQ22_A"
$PN"181"141;
"DQ21_A"
$PN"38"140;
"DQ20_A"
$PN"36"139;
"DQ19_A"
$PN"176"138;
"DQ18_A"
$PN"174"137;
"DQ17_A"
$PN"31"136;
"DQ16_A"
$PN"29"135;
"DQ15_A"
$PN"172"134;
"DQ14_A"
$PN"170"133;
"DQ13_A"
$PN"27"132;
"DQ12_A"
$PN"25"131;
"DQ11_A"
$PN"165"130;
"DQ10_A"
$PN"163"78;
"DQ9_A"
$PN"20"129;
"DQ8_A"
$PN"18"128;
"DQ7_A"
$PN"161"127;
"DQ6_A"
$PN"159"126;
"DQ5_A"
$PN"16"125;
"DQ4_A"
$PN"14"124;
"DQ3_A"
$PN"154"123;
"DQ2_A"
$PN"152"122;
"DQ1_A"
$PN"9"121;
"DQ0_A"
$PN"7"120;
"DQ31_B"
$PN"287"119;
"DQ30_B"
$PN"285"83;
"DQ29_B"
$PN"142"118;
"DQ28_B"
$PN"140"117;
"DQ27_B"
$PN"280"116;
"DQ26_B"
$PN"278"115;
"DQ25_B"
$PN"135"114;
"DQ24_B"
$PN"133"113;
"DQ23_B"
$PN"276"112;
"DQ22_B"
$PN"274"111;
"DQ21_B"
$PN"131"110;
"DQ20_B"
$PN"129"109;
"DQ19_B"
$PN"269"108;
"DQ18_B"
$PN"267"107;
"DQ17_B"
$PN"124"106;
"DQ16_B"
$PN"122"105;
"DQ15_B"
$PN"265"104;
"DQ14_B"
$PN"263"103;
"DQ13_B"
$PN"120"102;
"DQ12_B"
$PN"118"101;
"DQ11_B"
$PN"258"100;
"DQ10_B"
$PN"256"99;
"DQ9_B"
$PN"113"98;
"DQ8_B"
$PN"111"97;
"DQ7_B"
$PN"254"96;
"DQ6_B"
$PN"252"95;
"DQ5_B"
$PN"109"94;
"DQ4_B"
$PN"107"93;
"DQ3_B"
$PN"247"92;
"DQ2_B"
$PN"245"91;
"DQ1_B"
$PN"102"90;
"DQ0_B"
$PN"100"89;
"HSA"
$PN"148"20;
"HSCL"
$PN"4"24;
"HSDA"
$PN"5"21;
"LBD||RSP_A_N"
$PN"86"88;
"LBS||RSP_B_N"
$PN"87"87;
"PAR_A"
$PN"74"86;
"PAR_B"
$PN"227"85;
"PWR_GOOD||FAIL_N"
$PN"147"26;
"RESET_N \B"
$PN"207"23;
"RFU6"
$PN"232"27;
"RFU5"
$PN"231"29;
"RFU4"
$PN"220"84;
"RFU3"
$PN"150"30;
"RFU2"
$PN"149"28;
"RFU1"
$PN"144"31;
"RFU0"
$PN"2"32;
"VIN_MGMT"
$PN"3"4;
%"TAP"
"1","(-2225,2250)","2","standard","I26";
;
CDS_LIB"standard"
BODY_TYPE"PLUMBING"
HDL_TAP"TRUE";
"B \NAC \NWC"12;
"S \NAC"
BN"1"74;
%"TAP"
"1","(-2225,2200)","2","standard","I27";
;
CDS_LIB"standard"
BODY_TYPE"PLUMBING"
HDL_TAP"TRUE";
"B \NAC \NWC"12;
"S \NAC"
BN"0"73;
%"TAP"
"1","(-2225,2300)","2","standard","I28";
;
CDS_LIB"standard"
BODY_TYPE"PLUMBING"
HDL_TAP"TRUE";
"B \NAC \NWC"12;
"S \NAC"
BN"2"75;
%"TAP"
"1","(-2225,2350)","2","standard","I29";
;
CDS_LIB"standard"
BODY_TYPE"PLUMBING"
HDL_TAP"TRUE";
"B \NAC \NWC"12;
"S \NAC"
BN"3"76;
%"Q_RES"
"2","(-2000,250)","0","pure_quanta","I3";
;
PART_NUMBER"CS32322FB03"
VALUE"23.2K"
TOLERANCE"1%"
MATERIAL"CHIP"
WATTAGE"1/16W"
PACK_TYPE"0402LF"
$LOCATION"R44"
CDS_LIB"pure_quanta"
CDS_LOCATION"R44"
$SEC"1"
CDS_SEC"1";
"A"
$PN"1"178;
"B"
$PN"2"9;
%"TAP"
"1","(-2225,2400)","2","standard","I30";
;
CDS_LIB"standard"
BODY_TYPE"PLUMBING"
HDL_TAP"TRUE";
"B \NAC \NWC"12;
"S \NAC"
BN"4"152;
%"TAP"
"1","(-2225,2500)","2","standard","I31";
;
CDS_LIB"standard"
BODY_TYPE"PLUMBING"
HDL_TAP"TRUE";
"B \NAC \NWC"12;
"S \NAC"
BN"6"154;
%"TAP"
"1","(-2225,2450)","2","standard","I32";
;
CDS_LIB"standard"
BODY_TYPE"PLUMBING"
HDL_TAP"TRUE";
"B \NAC \NWC"12;
"S \NAC"
BN"5"153;
%"TAP"
"1","(-575,1250)","0","standard","I33";
;
CDS_LIB"standard"
BODY_TYPE"PLUMBING"
HDL_TAP"TRUE";
"B \NAC \NWC"15;
"S \NAC"
BN"1"90;
%"TAP"
"1","(-575,1200)","0","standard","I34";
;
CDS_LIB"standard"
BODY_TYPE"PLUMBING"
HDL_TAP"TRUE";
"B \NAC \NWC"15;
"S \NAC"
BN"0"89;
%"TAP"
"1","(-575,1350)","0","standard","I35";
;
CDS_LIB"standard"
BODY_TYPE"PLUMBING"
HDL_TAP"TRUE";
"B \NAC \NWC"15;
"S \NAC"
BN"3"92;
%"TAP"
"1","(-575,1300)","0","standard","I36";
;
CDS_LIB"standard"
BODY_TYPE"PLUMBING"
HDL_TAP"TRUE";
"B \NAC \NWC"15;
"S \NAC"
BN"2"91;
%"TAP"
"1","(-575,1450)","0","standard","I37";
;
CDS_LIB"standard"
BODY_TYPE"PLUMBING"
HDL_TAP"TRUE";
"B \NAC \NWC"15;
"S \NAC"
BN"5"94;
%"TAP"
"1","(-575,1400)","0","standard","I38";
;
CDS_LIB"standard"
BODY_TYPE"PLUMBING"
HDL_TAP"TRUE";
"B \NAC \NWC"15;
"S \NAC"
BN"4"93;
%"TAP"
"1","(-575,1500)","0","standard","I39";
;
CDS_LIB"standard"
BODY_TYPE"PLUMBING"
HDL_TAP"TRUE";
"B \NAC \NWC"15;
"S \NAC"
BN"6"95;
%"TAP"
"1","(-575,1550)","0","standard","I40";
;
CDS_LIB"standard"
BODY_TYPE"PLUMBING"
HDL_TAP"TRUE";
"B \NAC \NWC"15;
"S \NAC"
BN"7"96;
%"TAP"
"1","(-575,1600)","0","standard","I41";
;
CDS_LIB"standard"
BODY_TYPE"PLUMBING"
HDL_TAP"TRUE";
"B \NAC \NWC"15;
"S \NAC"
BN"8"97;
%"TAP"
"1","(-575,1650)","0","standard","I42";
;
CDS_LIB"standard"
BODY_TYPE"PLUMBING"
HDL_TAP"TRUE";
"B \NAC \NWC"15;
"S \NAC"
BN"9"98;
%"TAP"
"1","(-575,1750)","0","standard","I43";
;
CDS_LIB"standard"
BODY_TYPE"PLUMBING"
HDL_TAP"TRUE";
"B \NAC \NWC"15;
"S \NAC"
BN"11"100;
%"TAP"
"1","(-575,1700)","0","standard","I44";
;
CDS_LIB"standard"
BODY_TYPE"PLUMBING"
HDL_TAP"TRUE";
"B \NAC \NWC"15;
"S \NAC"
BN"10"99;
%"TAP"
"1","(-575,1950)","0","standard","I45";
;
CDS_LIB"standard"
BODY_TYPE"PLUMBING"
HDL_TAP"TRUE";
"B \NAC \NWC"15;
"S \NAC"
BN"15"104;
%"TAP"
"1","(-575,2000)","0","standard","I46";
;
CDS_LIB"standard"
BODY_TYPE"PLUMBING"
HDL_TAP"TRUE";
"B \NAC \NWC"15;
"S \NAC"
BN"16"105;
%"TAP"
"1","(-575,1900)","0","standard","I47";
;
CDS_LIB"standard"
BODY_TYPE"PLUMBING"
HDL_TAP"TRUE";
"B \NAC \NWC"15;
"S \NAC"
BN"14"103;
%"TAP"
"1","(-575,1850)","0","standard","I48";
;
CDS_LIB"standard"
BODY_TYPE"PLUMBING"
HDL_TAP"TRUE";
"B \NAC \NWC"15;
"S \NAC"
BN"13"102;
%"TAP"
"1","(-575,1800)","0","standard","I49";
;
CDS_LIB"standard"
BODY_TYPE"PLUMBING"
HDL_TAP"TRUE";
"B \NAC \NWC"15;
"S \NAC"
BN"12"101;
%"TAP"
"1","(-575,2250)","0","standard","I50";
;
CDS_LIB"standard"
BODY_TYPE"PLUMBING"
HDL_TAP"TRUE";
"B \NAC \NWC"15;
"S \NAC"
BN"21"110;
%"TAP"
"1","(-575,2200)","0","standard","I51";
;
CDS_LIB"standard"
BODY_TYPE"PLUMBING"
HDL_TAP"TRUE";
"B \NAC \NWC"15;
"S \NAC"
BN"20"109;
%"TAP"
"1","(-575,2150)","0","standard","I52";
;
CDS_LIB"standard"
BODY_TYPE"PLUMBING"
HDL_TAP"TRUE";
"B \NAC \NWC"15;
"S \NAC"
BN"19"108;
%"TAP"
"1","(-575,2100)","0","standard","I53";
;
CDS_LIB"standard"
BODY_TYPE"PLUMBING"
HDL_TAP"TRUE";
"B \NAC \NWC"15;
"S \NAC"
BN"18"107;
%"TAP"
"1","(-575,2050)","0","standard","I54";
;
CDS_LIB"standard"
BODY_TYPE"PLUMBING"
HDL_TAP"TRUE";
"B \NAC \NWC"15;
"S \NAC"
BN"17"106;
%"TAP"
"1","(-575,2450)","0","standard","I55";
;
CDS_LIB"standard"
BODY_TYPE"PLUMBING"
HDL_TAP"TRUE";
"B \NAC \NWC"15;
"S \NAC"
BN"25"114;
%"TAP"
"1","(-575,2500)","0","standard","I56";
;
CDS_LIB"standard"
BODY_TYPE"PLUMBING"
HDL_TAP"TRUE";
"B \NAC \NWC"15;
"S \NAC"
BN"26"115;
%"TAP"
"1","(-575,2300)","0","standard","I57";
;
CDS_LIB"standard"
BODY_TYPE"PLUMBING"
HDL_TAP"TRUE";
"B \NAC \NWC"15;
"S \NAC"
BN"22"111;
%"TAP"
"1","(-575,2400)","0","standard","I58";
;
CDS_LIB"standard"
BODY_TYPE"PLUMBING"
HDL_TAP"TRUE";
"B \NAC \NWC"15;
"S \NAC"
BN"24"113;
%"TAP"
"1","(-575,2350)","0","standard","I59";
;
CDS_LIB"standard"
BODY_TYPE"PLUMBING"
HDL_TAP"TRUE";
"B \NAC \NWC"15;
"S \NAC"
BN"23"112;
%"TAP"
"1","(-2225,2550)","2","standard","I60";
;
CDS_LIB"standard"
BODY_TYPE"PLUMBING"
HDL_TAP"TRUE";
"B \NAC \NWC"12;
"S \NAC"
BN"7"174;
%"TAP"
"1","(-2225,2650)","2","standard","I61";
;
CDS_LIB"standard"
BODY_TYPE"PLUMBING"
HDL_TAP"TRUE";
"B \NAC \NWC"11;
"S \NAC"
BN"0"155;
%"TAP"
"1","(-2225,2700)","2","standard","I62";
;
CDS_LIB"standard"
BODY_TYPE"PLUMBING"
HDL_TAP"TRUE";
"B \NAC \NWC"11;
"S \NAC"
BN"1"175;
%"TAP"
"1","(-2225,2750)","2","standard","I63";
;
CDS_LIB"standard"
BODY_TYPE"PLUMBING"
HDL_TAP"TRUE";
"B \NAC \NWC"11;
"S \NAC"
BN"2"156;
%"TAP"
"1","(-2225,2800)","2","standard","I64";
;
CDS_LIB"standard"
BODY_TYPE"PLUMBING"
HDL_TAP"TRUE";
"B \NAC \NWC"11;
"S \NAC"
BN"3"157;
%"TAP"
"1","(-2225,2850)","2","standard","I65";
;
CDS_LIB"standard"
BODY_TYPE"PLUMBING"
HDL_TAP"TRUE";
"B \NAC \NWC"11;
"S \NAC"
BN"4"82;
%"TAP"
"1","(-2225,2900)","2","standard","I66";
;
CDS_LIB"standard"
BODY_TYPE"PLUMBING"
HDL_TAP"TRUE";
"B \NAC \NWC"11;
"S \NAC"
BN"5"158;
%"TAP"
"1","(-2225,3000)","2","standard","I67";
;
CDS_LIB"standard"
BODY_TYPE"PLUMBING"
HDL_TAP"TRUE";
"B \NAC \NWC"11;
"S \NAC"
BN"7"176;
%"TAP"
"1","(-2225,2950)","2","standard","I68";
;
CDS_LIB"standard"
BODY_TYPE"PLUMBING"
HDL_TAP"TRUE";
"B \NAC \NWC"11;
"S \NAC"
BN"6"159;
%"TAP"
"1","(-2225,3800)","2","standard","I69";
;
CDS_LIB"standard"
BODY_TYPE"PLUMBING"
HDL_TAP"TRUE";
"B \NAC \NWC"14;
"S \NAC"
BN"2"168;
%"TAP"
"1","(-2225,3750)","2","standard","I70";
;
CDS_LIB"standard"
BODY_TYPE"PLUMBING"
HDL_TAP"TRUE";
"B \NAC \NWC"14;
"S \NAC"
BN"1"170;
%"TAP"
"1","(-2225,3700)","2","standard","I71";
;
CDS_LIB"standard"
BODY_TYPE"PLUMBING"
HDL_TAP"TRUE";
"B \NAC \NWC"14;
"S \NAC"
BN"0"172;
%"TAP"
"1","(-2225,3900)","2","standard","I72";
;
CDS_LIB"standard"
BODY_TYPE"PLUMBING"
HDL_TAP"TRUE";
"B \NAC \NWC"14;
"S \NAC"
BN"4"164;
%"TAP"
"1","(-2225,3850)","2","standard","I73";
;
CDS_LIB"standard"
BODY_TYPE"PLUMBING"
HDL_TAP"TRUE";
"B \NAC \NWC"14;
"S \NAC"
BN"3"166;
%"TAP"
"1","(-2225,3950)","2","standard","I74";
;
CDS_LIB"standard"
BODY_TYPE"PLUMBING"
HDL_TAP"TRUE";
"B \NAC \NWC"14;
"S \NAC"
BN"5"162;
%"TAP"
"1","(-2225,4000)","2","standard","I75";
;
CDS_LIB"standard"
BODY_TYPE"PLUMBING"
HDL_TAP"TRUE";
"B \NAC \NWC"14;
"S \NAC"
BN"6"160;
%"TAP"
"1","(-2225,4100)","2","standard","I76";
;
CDS_LIB"standard"
BODY_TYPE"PLUMBING"
HDL_TAP"TRUE";
"B \NAC \NWC"13;
"S \NAC"
BN"0"173;
%"TAP"
"1","(-2225,4150)","2","standard","I77";
;
CDS_LIB"standard"
BODY_TYPE"PLUMBING"
HDL_TAP"TRUE";
"B \NAC \NWC"13;
"S \NAC"
BN"1"171;
%"TAP"
"1","(-2225,4200)","2","standard","I78";
;
CDS_LIB"standard"
BODY_TYPE"PLUMBING"
HDL_TAP"TRUE";
"B \NAC \NWC"13;
"S \NAC"
BN"2"169;
%"TAP"
"1","(-2225,4250)","2","standard","I79";
;
CDS_LIB"standard"
BODY_TYPE"PLUMBING"
HDL_TAP"TRUE";
"B \NAC \NWC"13;
"S \NAC"
BN"3"167;
%"TAP"
"1","(-2225,4300)","2","standard","I80";
;
CDS_LIB"standard"
BODY_TYPE"PLUMBING"
HDL_TAP"TRUE";
"B \NAC \NWC"13;
"S \NAC"
BN"4"165;
%"TAP"
"1","(-2225,4400)","2","standard","I81";
;
CDS_LIB"standard"
BODY_TYPE"PLUMBING"
HDL_TAP"TRUE";
"B \NAC \NWC"13;
"S \NAC"
BN"6"161;
%"TAP"
"1","(-2225,4350)","2","standard","I82";
;
CDS_LIB"standard"
BODY_TYPE"PLUMBING"
HDL_TAP"TRUE";
"B \NAC \NWC"13;
"S \NAC"
BN"5"163;
%"TAP"
"1","(-575,2750)","0","standard","I83";
;
CDS_LIB"standard"
BODY_TYPE"PLUMBING"
HDL_TAP"TRUE";
"B \NAC \NWC"15;
"S \NAC"
BN"31"119;
%"TAP"
"1","(-575,2700)","0","standard","I84";
;
CDS_LIB"standard"
BODY_TYPE"PLUMBING"
HDL_TAP"TRUE";
"B \NAC \NWC"15;
"S \NAC"
BN"30"83;
%"TAP"
"1","(-575,2650)","0","standard","I85";
;
CDS_LIB"standard"
BODY_TYPE"PLUMBING"
HDL_TAP"TRUE";
"B \NAC \NWC"15;
"S \NAC"
BN"29"118;
%"TAP"
"1","(-575,2600)","0","standard","I86";
;
CDS_LIB"standard"
BODY_TYPE"PLUMBING"
HDL_TAP"TRUE";
"B \NAC \NWC"15;
"S \NAC"
BN"28"117;
%"TAP"
"1","(-575,2550)","0","standard","I87";
;
CDS_LIB"standard"
BODY_TYPE"PLUMBING"
HDL_TAP"TRUE";
"B \NAC \NWC"15;
"S \NAC"
BN"27"116;
%"TAP"
"1","(-575,2850)","0","standard","I88";
;
CDS_LIB"standard"
BODY_TYPE"PLUMBING"
HDL_TAP"TRUE";
"B \NAC \NWC"10;
"S \NAC"
BN"0"120;
%"TAP"
"1","(-575,2900)","0","standard","I89";
;
CDS_LIB"standard"
BODY_TYPE"PLUMBING"
HDL_TAP"TRUE";
"B \NAC \NWC"10;
"S \NAC"
BN"1"121;
%"TAP"
"1","(-575,3000)","0","standard","I90";
;
CDS_LIB"standard"
BODY_TYPE"PLUMBING"
HDL_TAP"TRUE";
"B \NAC \NWC"10;
"S \NAC"
BN"3"123;
%"TAP"
"1","(-575,3050)","0","standard","I91";
;
CDS_LIB"standard"
BODY_TYPE"PLUMBING"
HDL_TAP"TRUE";
"B \NAC \NWC"10;
"S \NAC"
BN"4"124;
%"TAP"
"1","(-575,2950)","0","standard","I92";
;
CDS_LIB"standard"
BODY_TYPE"PLUMBING"
HDL_TAP"TRUE";
"B \NAC \NWC"10;
"S \NAC"
BN"2"122;
%"TAP"
"1","(-575,3100)","0","standard","I93";
;
CDS_LIB"standard"
BODY_TYPE"PLUMBING"
HDL_TAP"TRUE";
"B \NAC \NWC"10;
"S \NAC"
BN"5"125;
%"TAP"
"1","(-575,3150)","0","standard","I94";
;
CDS_LIB"standard"
BODY_TYPE"PLUMBING"
HDL_TAP"TRUE";
"B \NAC \NWC"10;
"S \NAC"
BN"6"126;
%"TAP"
"1","(-575,3300)","0","standard","I95";
;
CDS_LIB"standard"
BODY_TYPE"PLUMBING"
HDL_TAP"TRUE";
"B \NAC \NWC"10;
"S \NAC"
BN"9"129;
%"TAP"
"1","(-575,3200)","0","standard","I96";
;
CDS_LIB"standard"
BODY_TYPE"PLUMBING"
HDL_TAP"TRUE";
"B \NAC \NWC"10;
"S \NAC"
BN"7"127;
%"TAP"
"1","(-575,3250)","0","standard","I97";
;
CDS_LIB"standard"
BODY_TYPE"PLUMBING"
HDL_TAP"TRUE";
"B \NAC \NWC"10;
"S \NAC"
BN"8"128;
%"TAP"
"1","(-575,3500)","0","standard","I98";
;
CDS_LIB"standard"
BODY_TYPE"PLUMBING"
HDL_TAP"TRUE";
"B \NAC \NWC"10;
"S \NAC"
BN"13"132;
%"TAP"
"1","(-575,3450)","0","standard","I99";
;
CDS_LIB"standard"
BODY_TYPE"PLUMBING"
HDL_TAP"TRUE";
"B \NAC \NWC"10;
"S \NAC"
BN"12"131;
END.
